(kicad_pcb
	(version 20260206)
	(generator "pcbnew")
	(generator_version "10.0")
	(general
		(thickness 1.6)
		(legacy_teardrops no)
	)
	(paper "A4")
	(title_block
		(title "peb — Lightning_PEB_BRD.brd")
		(comment 1 "Lightning (Wiwynn / Facebook NVMe JBOF) / footprints 957-962 of 2563")
	)
	(layers
		(0 "F.Cu" signal "TOP")
		(4 "In1.Cu" signal "L2GND")
		(6 "In2.Cu" signal "L3")
		(8 "In3.Cu" signal "L4VCC")
		(10 "In4.Cu" signal "L5VCC")
		(12 "In5.Cu" signal "L6")
		(14 "In6.Cu" signal "L7GND")
		(2 "B.Cu" signal "BOTTOM")
		(9 "F.Adhes" user "F.Adhesive")
		(11 "B.Adhes" user "B.Adhesive")
		(13 "F.Paste" user "Package Geometry/Pastemask Top")
		(15 "B.Paste" user "Package Geometry/Pastemask Bottom")
		(5 "F.SilkS" user "Ref Des/Silkscreen Top")
		(7 "B.SilkS" user "Ref Des/Silkscreen Bottom")
		(1 "F.Mask" user "Board Geometry/Soldermask Top")
		(3 "B.Mask" user "Board Geometry/Soldermask Bottom")
		(17 "Dwgs.User" user "User.Drawings")
		(19 "Cmts.User" user "User.Comments")
		(21 "Eco1.User" user "User.Eco1")
		(23 "Eco2.User" user "User.Eco2")
		(25 "Edge.Cuts" user "Board Geometry/Outline")
		(27 "Margin" user)
		(31 "F.CrtYd" user "Package Geometry/Place Bound Top")
		(29 "B.CrtYd" user "Package Geometry/Place Bound Bottom")
		(35 "F.Fab" user "Ref Des/Assembly Top")
		(33 "B.Fab" user "Ref Des/Assembly Bottom")
	)
	(footprint ""
		(layer "F.Cu")
		(at 64.447674 -67.12712 180)
		(property "Reference" "U19"
			(at 0 0 180)
			(layer "F.SilkS")
			(hide yes)
			(effects
				(font
					(size 1.27 1.27)
				)
			)
		)
		(property "Value" "MX25L25635FMI-10G-GP"
			(at 0 -14.6812 180)
			(unlocked yes)
			(layer "F.Fab")
			(hide yes)
			(effects
				(font
					(size 1.016 1.016)
					(thickness 0.1524)
				)
			)
		)
		(property "Device Type" "SOIC16-6H105"
			(at 0 -16.2052 180)
			(unlocked yes)
			(layer "F.Fab")
			(hide yes)
			(effects
				(font
					(size 1.016 1.016)
					(thickness 0.1524)
				)
			)
		)
		(duplicate_pad_numbers_are_jumpers no)
		(fp_line
			(start 4.7498 3.2258)
			(end -5.588 3.2258)
			(stroke
				(width 0.1524)
				(type default)
			)
			(layer "F.SilkS")
		)
		(fp_line
			(start 4.7498 -3.2258)
			(end 4.7498 3.2258)
			(stroke
				(width 0.1524)
				(type default)
			)
			(layer "F.SilkS")
		)
		(fp_line
			(start -5.08762 0)
			(end -5.588 0.50038)
			(stroke
				(width 0.1524)
				(type default)
			)
			(layer "F.SilkS")
		)
		(fp_line
			(start -5.4102 3.2258)
			(end -5.4102 5.7912)
			(stroke
				(width 0.508)
				(type default)
			)
			(layer "F.SilkS")
		)
		(fp_line
			(start -5.588 3.2258)
			(end -5.588 -3.2258)
			(stroke
				(width 0.1524)
				(type default)
			)
			(layer "F.SilkS")
		)
		(fp_line
			(start -5.588 -0.50038)
			(end -5.08762 0)
			(stroke
				(width 0.1524)
				(type default)
			)
			(layer "F.SilkS")
		)
		(fp_line
			(start -5.588 -3.2258)
			(end 4.7498 -3.2258)
			(stroke
				(width 0.1524)
				(type default)
			)
			(layer "F.SilkS")
		)
		(fp_poly
			(pts
				(xy -4.764786 -3.2258) (xy 4.7625 -3.2258) (xy 4.7625 3.2258) (xy -4.764786 3.2258)
			)
			(stroke
				(width 0)
				(type default)
			)
			(fill yes)
			(layer "F.SilkS")
		)
		(fp_poly
			(pts
				(xy -5.6642 6.0452) (xy 5.6642 6.0452) (xy 5.6642 -6.0452) (xy -5.6642 -6.0452)
			)
			(stroke
				(width 0)
				(type default)
			)
			(fill no)
			(layer "F.CrtYd")
		)
		(fp_poly
			(pts
				(xy -5.6642 -6.0452) (xy 5.6642 -6.0452) (xy 5.6642 6.0452) (xy -5.6642 6.0452)
			)
			(stroke
				(width 0)
				(type default)
			)
			(fill no)
			(layer "F.Fab")
		)
		(pad "1" smd rect
			(at -4.445 4.71805 180)
			(size 0.635 1.651)
			(layers "F.Cu" "F.Mask" "F.Paste")
			(net "PU_IBMC_BT_HOLD_N")
		)
		(pad "2" smd rect
			(at -3.175 4.71805 180)
			(size 0.635 1.651)
			(layers "F.Cu" "F.Mask" "F.Paste")
			(net "P3V3_STBY")
		)
		(pad "3" smd rect
			(at -1.905 4.71805 180)
			(size 0.635 1.651)
			(layers "F.Cu" "F.Mask" "F.Paste")
			(net "U19_PERST_N")
		)
		(pad "4" smd rect
			(at -0.635 4.71805 180)
			(size 0.635 1.651)
			(layers "F.Cu" "F.Mask" "F.Paste")
			(net "Net_32")
		)
		(pad "5" smd rect
			(at 0.635 4.71805 180)
			(size 0.635 1.651)
			(layers "F.Cu" "F.Mask" "F.Paste")
			(net "Net_31")
		)
		(pad "6" smd rect
			(at 1.905 4.71805 180)
			(size 0.635 1.651)
			(layers "F.Cu" "F.Mask" "F.Paste")
			(net "Net_30")
		)
		(pad "7" smd rect
			(at 3.175 4.71805 180)
			(size 0.635 1.651)
			(layers "F.Cu" "F.Mask" "F.Paste")
			(net "FLA_CS1_R")
		)
		(pad "8" smd rect
			(at 4.445 4.71805 180)
			(size 0.635 1.651)
			(layers "F.Cu" "F.Mask" "F.Paste")
			(net "ROMD2_R")
		)
		(pad "9" smd rect
			(at 4.445 -4.71805 180)
			(size 0.635 1.651)
			(layers "F.Cu" "F.Mask" "F.Paste")
			(net "FLA_WPN")
		)
		(pad "10" smd rect
			(at 3.175 -4.71805 180)
			(size 0.635 1.651)
			(layers "F.Cu" "F.Mask" "F.Paste")
			(net "GND")
		)
		(pad "11" smd rect
			(at 1.905 -4.71805 180)
			(size 0.635 1.651)
			(layers "F.Cu" "F.Mask" "F.Paste")
			(net "Net_29")
		)
		(pad "12" smd rect
			(at 0.635 -4.71805 180)
			(size 0.635 1.651)
			(layers "F.Cu" "F.Mask" "F.Paste")
			(net "Net_28")
		)
		(pad "13" smd rect
			(at -0.635 -4.71805 180)
			(size 0.635 1.651)
			(layers "F.Cu" "F.Mask" "F.Paste")
			(net "Net_27")
		)
		(pad "14" smd rect
			(at -1.905 -4.71805 180)
			(size 0.635 1.651)
			(layers "F.Cu" "F.Mask" "F.Paste")
			(net "Net_26")
		)
		(pad "15" smd rect
			(at -3.175 -4.71805 180)
			(size 0.635 1.651)
			(layers "F.Cu" "F.Mask" "F.Paste")
			(net "ROMD1_R")
		)
		(pad "16" smd rect
			(at -4.445 -4.71805 180)
			(size 0.635 1.651)
			(layers "F.Cu" "F.Mask" "F.Paste")
			(net "ROMD0_R")
		)
	)
	(footprint ""
		(layer "F.Cu")
		(at 303.00803 -212.420454 180)
		(property "Reference" "C75"
			(at 0 0 180)
			(layer "F.SilkS")
			(hide yes)
			(effects
				(font
					(size 1.27 1.27)
				)
			)
		)
		(property "Value" "SCD22U10V2KX-1GP"
			(at 1.1811 -2.7051 180)
			(unlocked yes)
			(layer "F.Fab")
			(hide yes)
			(effects
				(font
					(size 1.016 1.016)
					(thickness 0.1524)
				)
			)
		)
		(property "Device Type" "C402H22"
			(at 1.1811 -4.2291 180)
			(unlocked yes)
			(layer "F.Fab")
			(hide yes)
			(effects
				(font
					(size 1.016 1.016)
					(thickness 0.1524)
				)
			)
		)
		(duplicate_pad_numbers_are_jumpers no)
		(fp_rect
			(start -0.4318 0.9525)
			(end 0.4318 -0.9525)
			(stroke
				(width 0)
				(type default)
			)
			(fill no)
			(layer "F.CrtYd")
		)
		(fp_rect
			(start -0.4318 0.9525)
			(end 0.4318 -0.9525)
			(stroke
				(width 0)
				(type default)
			)
			(fill no)
			(layer "F.Fab")
		)
		(pad "1" smd custom
			(at 0 -0.4445 180)
			(size 0.1524 0.1524)
			(layers "F.Cu" "F.Mask" "F.Paste")
			(net "PCIE_TX_CAP_N26")
			(options
				(clearance outline)
				(anchor circle)
			)
			(primitives
				(gr_poly
					(pts
						(arc
							(start 0.3048 -0.2032)
							(mid 0.275042 -0.275042)
							(end 0.2032 -0.3048)
						)
						(arc
							(start -0.2032 -0.3048)
							(mid -0.275042 -0.275042)
							(end -0.3048 -0.2032)
						)
						(arc
							(start -0.3048 0.2032)
							(mid -0.275042 0.275042)
							(end -0.2032 0.3048)
						)
						(arc
							(start 0.2032 0.3048)
							(mid 0.275042 0.275042)
							(end 0.3048 0.2032)
						)
					)
					(width 0)
					(fill yes)
				)
			)
		)
		(pad "2" smd custom
			(at 0 0.4445 180)
			(size 0.1524 0.1524)
			(layers "F.Cu" "F.Mask" "F.Paste")
			(net "PCIE_TX_N26")
			(options
				(clearance outline)
				(anchor circle)
			)
			(primitives
				(gr_poly
					(pts
						(arc
							(start 0.3048 -0.2032)
							(mid 0.275042 -0.275042)
							(end 0.2032 -0.3048)
						)
						(arc
							(start -0.2032 -0.3048)
							(mid -0.275042 -0.275042)
							(end -0.3048 -0.2032)
						)
						(arc
							(start -0.3048 0.2032)
							(mid -0.275042 0.275042)
							(end -0.2032 0.3048)
						)
						(arc
							(start 0.2032 0.3048)
							(mid 0.275042 0.275042)
							(end 0.3048 0.2032)
						)
					)
					(width 0)
					(fill yes)
				)
			)
		)
	)
	(footprint ""
		(layer "F.Cu")
		(at 20.6502 -83.82 180)
		(property "Reference" "C643"
			(at 0 0 180)
			(layer "F.SilkS")
			(hide yes)
			(effects
				(font
					(size 1.27 1.27)
				)
			)
		)
		(property "Value" "SCD22U10V2KX-1GP"
			(at 1.1811 -2.7051 180)
			(unlocked yes)
			(layer "F.Fab")
			(hide yes)
			(effects
				(font
					(size 1.016 1.016)
					(thickness 0.1524)
				)
			)
		)
		(property "Device Type" "C402H22"
			(at 1.1811 -4.2291 180)
			(unlocked yes)
			(layer "F.Fab")
			(hide yes)
			(effects
				(font
					(size 1.016 1.016)
					(thickness 0.1524)
				)
			)
		)
		(duplicate_pad_numbers_are_jumpers no)
		(fp_rect
			(start -0.4318 0.9525)
			(end 0.4318 -0.9525)
			(stroke
				(width 0)
				(type default)
			)
			(fill no)
			(layer "F.CrtYd")
		)
		(fp_rect
			(start -0.4318 0.9525)
			(end 0.4318 -0.9525)
			(stroke
				(width 0)
				(type default)
			)
			(fill no)
			(layer "F.Fab")
		)
		(pad "1" smd custom
			(at 0 -0.4445 180)
			(size 0.1524 0.1524)
			(layers "F.Cu" "F.Mask" "F.Paste")
			(net "PCIE_RX_CAP_P78")
			(options
				(clearance outline)
				(anchor circle)
			)
			(primitives
				(gr_poly
					(pts
						(arc
							(start 0.3048 -0.2032)
							(mid 0.275042 -0.275042)
							(end 0.2032 -0.3048)
						)
						(arc
							(start -0.2032 -0.3048)
							(mid -0.275042 -0.275042)
							(end -0.3048 -0.2032)
						)
						(arc
							(start -0.3048 0.2032)
							(mid -0.275042 0.275042)
							(end -0.2032 0.3048)
						)
						(arc
							(start 0.2032 0.3048)
							(mid 0.275042 0.275042)
							(end 0.3048 0.2032)
						)
					)
					(width 0)
					(fill yes)
				)
			)
		)
		(pad "2" smd custom
			(at 0 0.4445 180)
			(size 0.1524 0.1524)
			(layers "F.Cu" "F.Mask" "F.Paste")
			(net "PCIE_RX_P78")
			(options
				(clearance outline)
				(anchor circle)
			)
			(primitives
				(gr_poly
					(pts
						(arc
							(start 0.3048 -0.2032)
							(mid 0.275042 -0.275042)
							(end 0.2032 -0.3048)
						)
						(arc
							(start -0.2032 -0.3048)
							(mid -0.275042 -0.275042)
							(end -0.3048 -0.2032)
						)
						(arc
							(start -0.3048 0.2032)
							(mid -0.275042 0.275042)
							(end -0.2032 0.3048)
						)
						(arc
							(start 0.2032 0.3048)
							(mid 0.275042 0.275042)
							(end 0.3048 0.2032)
						)
					)
					(width 0)
					(fill yes)
				)
			)
		)
	)
	(footprint ""
		(layer "F.Cu")
		(at 125.599952 -7.999984 90)
		(property "Reference" "LED10"
			(at 0 0 90)
			(layer "F.SilkS")
			(hide yes)
			(effects
				(font
					(size 1.27 1.27)
				)
			)
		)
		(property "Value" "LED-YG-51-GP"
			(at -2.6924 -1.4224 90)
			(unlocked yes)
			(layer "F.Fab")
			(hide yes)
			(effects
				(font
					(size 1.016 1.016)
					(thickness 0.1524)
				)
			)
		)
		(property "Device Type" "LED1608AKH40"
			(at -2.6924 -2.9464 90)
			(unlocked yes)
			(layer "F.Fab")
			(hide yes)
			(effects
				(font
					(size 1.016 1.016)
					(thickness 0.1524)
				)
			)
		)
		(duplicate_pad_numbers_are_jumpers no)
		(fp_line
			(start 0.6604 -1.3716)
			(end 0.6604 1.3716)
			(stroke
				(width 0.1524)
				(type default)
			)
			(layer "F.SilkS")
		)
		(fp_line
			(start -0.6604 -1.3716)
			(end 0.6604 -1.3716)
			(stroke
				(width 0.1524)
				(type default)
			)
			(layer "F.SilkS")
		)
		(fp_line
			(start 0.6604 1.3716)
			(end -0.6604 1.3716)
			(stroke
				(width 0.1524)
				(type default)
			)
			(layer "F.SilkS")
		)
		(fp_line
			(start -0.6604 1.3716)
			(end -0.6604 -1.3716)
			(stroke
				(width 0.1524)
				(type default)
			)
			(layer "F.SilkS")
		)
		(fp_line
			(start -0.5969 1.5494)
			(end 0.5842 1.5494)
			(stroke
				(width 0.508)
				(type default)
			)
			(layer "F.SilkS")
		)
		(fp_line
			(start 0.7493 1.651)
			(end 0.7493 1.1811)
			(stroke
				(width 0.3302)
				(type default)
			)
			(layer "F.SilkS")
		)
		(fp_line
			(start -0.7493 1.651)
			(end -0.7493 1.1811)
			(stroke
				(width 0.3302)
				(type default)
			)
			(layer "F.SilkS")
		)
		(fp_rect
			(start -0.6223 1.3335)
			(end 0.6223 -1.3335)
			(stroke
				(width 0)
				(type default)
			)
			(fill no)
			(layer "F.CrtYd")
		)
		(fp_rect
			(start -0.6223 1.3335)
			(end 0.6223 -1.3335)
			(stroke
				(width 0)
				(type default)
			)
			(fill no)
			(layer "F.Fab")
		)
		(pad "A" smd custom
			(at 0 -0.762 90)
			(size 0.2159 0.2159)
			(layers "F.Cu" "F.Mask" "F.Paste")
			(net "LED_R_3")
			(options
				(clearance outline)
				(anchor circle)
			)
			(primitives
				(gr_poly
					(pts
						(arc
							(start -0.3302 -0.4318)
							(mid -0.402042 -0.402042)
							(end -0.4318 -0.3302)
						)
						(arc
							(start -0.4318 0.3302)
							(mid -0.402042 0.402042)
							(end -0.3302 0.4318)
						)
						(arc
							(start 0.3302 0.4318)
							(mid 0.402042 0.402042)
							(end 0.4318 0.3302)
						)
						(arc
							(start 0.4318 -0.3302)
							(mid 0.402042 -0.402042)
							(end 0.3302 -0.4318)
						)
					)
					(width 0)
					(fill yes)
				)
			)
		)
		(pad "K" smd custom
			(at 0 0.762 90)
			(size 0.2159 0.2159)
			(layers "F.Cu" "F.Mask" "F.Paste")
			(net "LED_Q_3")
			(options
				(clearance outline)
				(anchor circle)
			)
			(primitives
				(gr_poly
					(pts
						(arc
							(start -0.3302 -0.4318)
							(mid -0.402042 -0.402042)
							(end -0.4318 -0.3302)
						)
						(arc
							(start -0.4318 0.3302)
							(mid -0.402042 0.402042)
							(end -0.3302 0.4318)
						)
						(arc
							(start 0.3302 0.4318)
							(mid 0.402042 0.402042)
							(end 0.4318 0.3302)
						)
						(arc
							(start 0.4318 -0.3302)
							(mid 0.402042 -0.402042)
							(end 0.3302 -0.4318)
						)
					)
					(width 0)
					(fill yes)
				)
			)
		)
	)
	(footprint ""
		(layer "F.Cu")
		(at 225.586798 -206.384906 90)
		(property "Reference" "C4128"
			(at 0 0 90)
			(layer "F.SilkS")
			(hide yes)
			(effects
				(font
					(size 1.27 1.27)
				)
			)
		)
		(property "Value" "SCD1U25V3KX-GP"
			(at 0 -2.8194 90)
			(unlocked yes)
			(layer "F.Fab")
			(hide yes)
			(effects
				(font
					(size 1.016 1.016)
					(thickness 0.1524)
				)
			)
		)
		(property "Device Type" "C603H36"
			(at 0 -4.3434 90)
			(unlocked yes)
			(layer "F.Fab")
			(hide yes)
			(effects
				(font
					(size 1.016 1.016)
					(thickness 0.1524)
				)
			)
		)
		(duplicate_pad_numbers_are_jumpers no)
		(fp_line
			(start 0.508 0)
			(end -0.508 0)
			(stroke
				(width 0.2032)
				(type default)
			)
			(layer "F.SilkS")
		)
		(fp_rect
			(start -0.5842 1.3335)
			(end 0.5842 -1.3335)
			(stroke
				(width 0)
				(type default)
			)
			(fill no)
			(layer "F.CrtYd")
		)
		(fp_rect
			(start -0.5842 1.3335)
			(end 0.5842 -1.3335)
			(stroke
				(width 0)
				(type default)
			)
			(fill no)
			(layer "F.Fab")
		)
		(pad "1" smd custom
			(at 0 -0.762 90)
			(size 0.2159 0.2159)
			(layers "F.Cu" "F.Mask" "F.Paste")
			(net "GND")
			(options
				(clearance outline)
				(anchor circle)
			)
			(primitives
				(gr_poly
					(pts
						(arc
							(start -0.3302 -0.4318)
							(mid -0.402042 -0.402042)
							(end -0.4318 -0.3302)
						)
						(arc
							(start -0.4318 0.3302)
							(mid -0.402042 0.402042)
							(end -0.3302 0.4318)
						)
						(arc
							(start 0.3302 0.4318)
							(mid 0.402042 0.402042)
							(end 0.4318 0.3302)
						)
						(arc
							(start 0.4318 -0.3302)
							(mid 0.402042 -0.402042)
							(end 0.3302 -0.4318)
						)
					)
					(width 0)
					(fill yes)
				)
			)
		)
		(pad "2" smd custom
			(at 0 0.762 90)
			(size 0.2159 0.2159)
			(layers "F.Cu" "F.Mask" "F.Paste")
			(net "SSD_PWREN12_R")
			(options
				(clearance outline)
				(anchor circle)
			)
			(primitives
				(gr_poly
					(pts
						(arc
							(start -0.3302 -0.4318)
							(mid -0.402042 -0.402042)
							(end -0.4318 -0.3302)
						)
						(arc
							(start -0.4318 0.3302)
							(mid -0.402042 0.402042)
							(end -0.3302 0.4318)
						)
						(arc
							(start 0.3302 0.4318)
							(mid 0.402042 0.402042)
							(end 0.4318 0.3302)
						)
						(arc
							(start 0.4318 -0.3302)
							(mid 0.402042 -0.402042)
							(end 0.3302 -0.4318)
						)
					)
					(width 0)
					(fill yes)
				)
			)
		)
	)
	(footprint ""
		(layer "F.Cu")
		(at 183.950102 -0.60452 -90)
		(property "Reference" "R670"
			(at 0 0 270)
			(layer "F.SilkS")
			(hide yes)
			(effects
				(font
					(size 1.27 1.27)
				)
			)
		)
		(property "Value" "0R2J-2-GP"
			(at 0.064008 -3.993896 270)
			(unlocked yes)
			(layer "F.Fab")
			(hide yes)
			(effects
				(font
					(size 1.016 1.016)
					(thickness 0.1524)
				)
			)
		)
		(property "Device Type" "R402H16"
			(at 0.064008 -5.517896 270)
			(unlocked yes)
			(layer "F.Fab")
			(hide yes)
			(effects
				(font
					(size 1.016 1.016)
					(thickness 0.1524)
				)
			)
		)
		(duplicate_pad_numbers_are_jumpers no)
		(fp_line
			(start -0.508 -0.9398)
			(end -0.508 0.9398)
			(stroke
				(width 0.1524)
				(type default)
			)
			(layer "F.SilkS")
		)
		(fp_line
			(start 0.508 -0.9398)
			(end -0.508 -0.9398)
			(stroke
				(width 0.1524)
				(type default)
			)
			(layer "F.SilkS")
		)
		(fp_rect
			(start -0.508 0.9398)
			(end 0.508 -0.9398)
			(stroke
				(width 0)
				(type default)
			)
			(fill no)
			(layer "F.CrtYd")
		)
		(fp_rect
			(start -0.508 0.9398)
			(end 0.508 -0.9398)
			(stroke
				(width 0)
				(type default)
			)
			(fill no)
			(layer "F.Fab")
		)
		(pad "1" smd custom
			(at 0 -0.4445 270)
			(size 0.1397 0.1397)
			(layers "F.Cu" "F.Mask" "F.Paste")
			(net "HOST1_RST_N_C")
			(options
				(clearance outline)
				(anchor circle)
			)
			(primitives
				(gr_poly
					(pts
						(arc
							(start -0.1778 -0.2794)
							(mid -0.249642 -0.249642)
							(end -0.2794 -0.1778)
						)
						(arc
							(start -0.2794 0.1778)
							(mid -0.249642 0.249642)
							(end -0.1778 0.2794)
						)
						(arc
							(start 0.1778 0.2794)
							(mid 0.249642 0.249642)
							(end 0.2794 0.1778)
						)
						(arc
							(start 0.2794 -0.1778)
							(mid 0.249642 -0.249642)
							(end 0.1778 -0.2794)
						)
					)
					(width 0)
					(fill yes)
				)
			)
		)
		(pad "2" smd custom
			(at 0 0.4445 270)
			(size 0.1397 0.1397)
			(layers "F.Cu" "F.Mask" "F.Paste")
			(net "P3V3_STBY")
			(options
				(clearance outline)
				(anchor circle)
			)
			(primitives
				(gr_poly
					(pts
						(arc
							(start -0.1778 -0.2794)
							(mid -0.249642 -0.249642)
							(end -0.2794 -0.1778)
						)
						(arc
							(start -0.2794 0.1778)
							(mid -0.249642 0.249642)
							(end -0.1778 0.2794)
						)
						(arc
							(start 0.1778 0.2794)
							(mid 0.249642 0.249642)
							(end 0.2794 0.1778)
						)
						(arc
							(start 0.2794 -0.1778)
							(mid 0.249642 -0.249642)
							(end 0.1778 -0.2794)
						)
					)
					(width 0)
					(fill yes)
				)
			)
		)
	)
)
